# T6G (Grand Teton) — schematic netlist excerpt (pin names and nets, part order shuffled) for the footprints in the layout excerpt that follows; sources: Cadence DE-HDL packaged netlist, KiCad conversion of 04192023_DAF0TMB3IC0_F0TG_MB_C_brd_V02_OCP.brd

PC2165  Q_CAP  1UF 25V 10% X6S  pkg C0402  page 141 : A = P12V_AUX ; B = GND
R59  Q_RES  22 1% CHIP  pkg 0402LF  page 132 : A = NCSI_BMC_CRS_DV_R ; B = RMII_OCP_BMC_CRSDV
R1112  Q_RES  10K 1% CHIP  pkg 0201LF  page 309 : A = GPIO2_RT_CPU0_P3 ; B = GND

(kicad_pcb
	(version 20260206)
	(generator "pcbnew")
	(generator_version "10.0")
	(general
		(thickness 1.6)
		(legacy_teardrops no)
	)
	(paper "A4")
	(title_block
		(title "04192023_DAF0TMB3IC0_F0TG_MB_C_brd_V02_OCP.brd")
		(comment 1 "Grand Teton / footprints 1939-1941 of 8354")
	)
	(layers
		(0 "F.Cu" signal "TOP")
		(4 "In1.Cu" signal "GND")
		(6 "In2.Cu" signal "IN1")
		(8 "In3.Cu" signal "GND1")
		(10 "In4.Cu" signal "IN2")
		(12 "In5.Cu" signal "GND2")
		(14 "In6.Cu" signal "IN3")
		(16 "In7.Cu" signal "GND3")
		(18 "In8.Cu" signal "VCC")
		(20 "In9.Cu" signal "VCC1")
		(22 "In10.Cu" signal "GND4")
		(24 "In11.Cu" signal "IN4")
		(26 "In12.Cu" signal "GND5")
		(28 "In13.Cu" signal "IN5")
		(30 "In14.Cu" signal "GND6")
		(32 "In15.Cu" signal "IN6")
		(34 "In16.Cu" signal "GND7")
		(2 "B.Cu" signal "BOTTOM")
		(9 "F.Adhes" user "F.Adhesive")
		(11 "B.Adhes" user "B.Adhesive")
		(13 "F.Paste" user "Package Geometry/Pastemask Top")
		(15 "B.Paste" user "Package Geometry/Pastemask Bottom")
		(5 "F.SilkS" user "Ref Des/Silkscreen Top")
		(7 "B.SilkS" user "Ref Des/Silkscreen Bottom")
		(1 "F.Mask" user "Board Geometry/Soldermask Top")
		(3 "B.Mask" user "Board Geometry/Soldermask Bottom")
		(17 "Dwgs.User" user "User.Drawings")
		(19 "Cmts.User" user "User.Comments")
		(21 "Eco1.User" user "User.Eco1")
		(23 "Eco2.User" user "User.Eco2")
		(25 "Edge.Cuts" user "Board Geometry/Outline")
		(27 "Margin" user)
		(31 "F.CrtYd" user "Package Geometry/Place Bound Top")
		(29 "B.CrtYd" user "Package Geometry/Place Bound Bottom")
		(35 "F.Fab" user "Ref Des/Assembly Top")
		(33 "B.Fab" user "Ref Des/Assembly Bottom")
	)
	(footprint ""
		(layer "F.Cu")
		(at 194.371722 -76.016866)
		(property "Reference" "R59"
			(at 0 0 0)
			(layer "F.SilkS")
			(hide yes)
			(effects
				(font
					(size 1.27 1.27)
				)
			)
		)
		(property "Value" ""
			(at 0 0 0)
			(layer "F.Fab")
			(effects
				(font
					(size 1.27 1.27)
				)
			)
		)
		(duplicate_pad_numbers_are_jumpers no)
		(fp_line
			(start -0.7874 -0.4064)
			(end 0.7874 -0.4064)
			(stroke
				(width 0.1524)
				(type default)
			)
			(layer "F.SilkS")
		)
		(fp_line
			(start -0.7874 0.4064)
			(end -0.7874 -0.4064)
			(stroke
				(width 0.1524)
				(type default)
			)
			(layer "F.SilkS")
		)
		(fp_line
			(start 0.7874 -0.4064)
			(end 0.7874 0.4064)
			(stroke
				(width 0.1524)
				(type default)
			)
			(layer "F.SilkS")
		)
		(fp_line
			(start 0.7874 0.4064)
			(end -0.7874 0.4064)
			(stroke
				(width 0.1524)
				(type default)
			)
			(layer "F.SilkS")
		)
		(fp_line
			(start -0.67945 -0.305054)
			(end -0.12065 -0.305054)
			(stroke
				(width 0.1)
				(type default)
			)
			(layer "F.Fab")
		)
		(fp_line
			(start -0.67945 0.3048)
			(end -0.67945 -0.305054)
			(stroke
				(width 0.1)
				(type default)
			)
			(layer "F.Fab")
		)
		(fp_line
			(start -0.12065 -0.305054)
			(end -0.12065 -0.2794)
			(stroke
				(width 0.1)
				(type default)
			)
			(layer "F.Fab")
		)
		(fp_line
			(start -0.12065 -0.2794)
			(end 0.12065 -0.2794)
			(stroke
				(width 0.1)
				(type default)
			)
			(layer "F.Fab")
		)
		(fp_line
			(start -0.12065 0.2794)
			(end -0.12065 0.3048)
			(stroke
				(width 0.1)
				(type default)
			)
			(layer "F.Fab")
		)
		(fp_line
			(start -0.12065 0.3048)
			(end -0.67945 0.3048)
			(stroke
				(width 0.1)
				(type default)
			)
			(layer "F.Fab")
		)
		(fp_line
			(start 0.120396 0.2794)
			(end -0.12065 0.2794)
			(stroke
				(width 0.1)
				(type default)
			)
			(layer "F.Fab")
		)
		(fp_line
			(start 0.120396 0.3048)
			(end 0.120396 0.2794)
			(stroke
				(width 0.1)
				(type default)
			)
			(layer "F.Fab")
		)
		(fp_line
			(start 0.12065 -0.3048)
			(end 0.67945 -0.3048)
			(stroke
				(width 0.1)
				(type default)
			)
			(layer "F.Fab")
		)
		(fp_line
			(start 0.12065 -0.2794)
			(end 0.12065 -0.3048)
			(stroke
				(width 0.1)
				(type default)
			)
			(layer "F.Fab")
		)
		(fp_line
			(start 0.67945 -0.3048)
			(end 0.67945 0.3048)
			(stroke
				(width 0.1)
				(type default)
			)
			(layer "F.Fab")
		)
		(fp_line
			(start 0.67945 0.3048)
			(end 0.120396 0.3048)
			(stroke
				(width 0.1)
				(type default)
			)
			(layer "F.Fab")
		)
		(pad "1" smd circle
			(at -0.40005 0)
			(size 0 0)
			(layers "F.Cu" "F.Mask" "F.Paste")
			(net "NCSI_BMC_CRS_DV_R")
		)
		(pad "2" smd circle
			(at 0.40005 0)
			(size 0 0)
			(layers "F.Cu" "F.Mask" "F.Paste")
			(net "RMII_OCP_BMC_CRSDV")
		)
	)
	(footprint ""
		(layer "F.Cu")
		(at 73.496678 -29.845762 90)
		(property "Reference" "PC2165"
			(at 0 0 90)
			(layer "F.SilkS")
			(hide yes)
			(effects
				(font
					(size 1.27 1.27)
				)
			)
		)
		(property "Value" ""
			(at 0 0 90)
			(layer "F.Fab")
			(effects
				(font
					(size 1.27 1.27)
				)
			)
		)
		(duplicate_pad_numbers_are_jumpers no)
		(fp_line
			(start 0.7874 -0.4064)
			(end 0.7874 0.4064)
			(stroke
				(width 0.1524)
				(type default)
			)
			(layer "F.SilkS")
		)
		(fp_line
			(start -0.7874 -0.4064)
			(end 0.7874 -0.4064)
			(stroke
				(width 0.1524)
				(type default)
			)
			(layer "F.SilkS")
		)
		(fp_line
			(start 0.7874 0.4064)
			(end -0.7874 0.4064)
			(stroke
				(width 0.1524)
				(type default)
			)
			(layer "F.SilkS")
		)
		(fp_line
			(start -0.7874 0.4064)
			(end -0.7874 -0.4064)
			(stroke
				(width 0.1524)
				(type default)
			)
			(layer "F.SilkS")
		)
		(fp_line
			(start -0.12065 -0.305054)
			(end -0.12065 -0.2794)
			(stroke
				(width 0.1)
				(type default)
			)
			(layer "F.Fab")
		)
		(fp_line
			(start -0.67945 -0.305054)
			(end -0.12065 -0.305054)
			(stroke
				(width 0.1)
				(type default)
			)
			(layer "F.Fab")
		)
		(fp_line
			(start 0.67945 -0.3048)
			(end 0.67945 0.3048)
			(stroke
				(width 0.1)
				(type default)
			)
			(layer "F.Fab")
		)
		(fp_line
			(start 0.12065 -0.3048)
			(end 0.67945 -0.3048)
			(stroke
				(width 0.1)
				(type default)
			)
			(layer "F.Fab")
		)
		(fp_line
			(start 0.12065 -0.2794)
			(end 0.12065 -0.3048)
			(stroke
				(width 0.1)
				(type default)
			)
			(layer "F.Fab")
		)
		(fp_line
			(start -0.12065 -0.2794)
			(end 0.12065 -0.2794)
			(stroke
				(width 0.1)
				(type default)
			)
			(layer "F.Fab")
		)
		(fp_line
			(start 0.120396 0.2794)
			(end -0.12065 0.2794)
			(stroke
				(width 0.1)
				(type default)
			)
			(layer "F.Fab")
		)
		(fp_line
			(start -0.12065 0.2794)
			(end -0.12065 0.3048)
			(stroke
				(width 0.1)
				(type default)
			)
			(layer "F.Fab")
		)
		(fp_line
			(start 0.67945 0.3048)
			(end 0.120396 0.3048)
			(stroke
				(width 0.1)
				(type default)
			)
			(layer "F.Fab")
		)
		(fp_line
			(start 0.120396 0.3048)
			(end 0.120396 0.2794)
			(stroke
				(width 0.1)
				(type default)
			)
			(layer "F.Fab")
		)
		(fp_line
			(start -0.12065 0.3048)
			(end -0.67945 0.3048)
			(stroke
				(width 0.1)
				(type default)
			)
			(layer "F.Fab")
		)
		(fp_line
			(start -0.67945 0.3048)
			(end -0.67945 -0.305054)
			(stroke
				(width 0.1)
				(type default)
			)
			(layer "F.Fab")
		)
		(pad "1" smd circle
			(at -0.40005 0 90)
			(size 0 0)
			(layers "F.Cu" "F.Mask" "F.Paste")
			(net "P12V_AUX")
		)
		(pad "2" smd circle
			(at 0.40005 0 90)
			(size 0 0)
			(layers "F.Cu" "F.Mask" "F.Paste")
			(net "GND")
		)
	)
	(footprint ""
		(layer "F.Cu")
		(at 366.36579 -393.96416)
		(property "Reference" "R1112"
			(at 0 0 0)
			(layer "F.SilkS")
			(hide yes)
			(effects
				(font
					(size 1.27 1.27)
				)
			)
		)
		(property "Value" ""
			(at 0 0 0)
			(layer "F.Fab")
			(effects
				(font
					(size 1.27 1.27)
				)
			)
		)
		(duplicate_pad_numbers_are_jumpers no)
		(fp_line
			(start -0.32512 -0.175006)
			(end 0.32512 -0.175006)
			(stroke
				(width 0.1)
				(type default)
			)
			(layer "F.Fab")
		)
		(fp_line
			(start -0.32512 0.175006)
			(end -0.32512 -0.175006)
			(stroke
				(width 0.1)
				(type default)
			)
			(layer "F.Fab")
		)
		(fp_line
			(start 0.32512 -0.175006)
			(end 0.32512 0.175006)
			(stroke
				(width 0.1)
				(type default)
			)
			(layer "F.Fab")
		)
		(fp_line
			(start 0.32512 0.175006)
			(end -0.32512 0.175006)
			(stroke
				(width 0.1)
				(type default)
			)
			(layer "F.Fab")
		)
		(pad "1" smd rect
			(at -0.2667 0)
			(size 0.3048 0.381)
			(layers "F.Cu" "F.Mask" "F.Paste")
			(net "GPIO2_RT_CPU0_P3")
		)
		(pad "2" smd rect
			(at 0.2667 0 180)
			(size 0.3048 0.381)
			(layers "F.Cu" "F.Mask" "F.Paste")
			(net "GND")
		)
	)
)
